# Bryce Canyon_Storage_Controller_Card_Stackup.xlsx — Storage_PCB_Test_Note (pcb-stackup)
| 編號(Number) | 內容(Item) | 附加檔案(Files) | 附加說明(Description) |
| 1 | Impedance traceability and test |  | 1、板廠在HVM量產階段採用AQL 0.65 正常檢驗水準二級來抽樣，利用Excel範本(PCB_Vendor_PCB_Number(XXXXX-SA)_Impedance_Report_Template_Date.xlsx)在量產階段(HVM 90天後)，不同lot 的量測結果分開於不同的分頁中，記錄其Min, Max, Mean, Median, Sigma, CP, CK, CPK等數值。 2、阻抗CPK的允收條件為 c= 0 (HVM 90天後)；阻抗數值的允收條件為 ±10%(EVT, DVT, PVT,HVM)。 3、阻抗測試條需擺放於折斷邊上。 |
